#ISCELL
  mstr_standard drawing *
  *
#ISCELL
  mstr_standard synonym *
  page1_1p
